# T6G (Grand Teton) — schematic netlist excerpt (pin names and nets, part order shuffled) for the footprints in the layout excerpt that follows; sources: Cadence DE-HDL packaged netlist, KiCad conversion of 04192023_DAF0TMB3IC0_F0TG_MB_C_brd_V02_OCP.brd

R2262  Q_RES  33.2 1% CHIP  pkg 0402LF  page 81 : A = FM_GPU_PWR_EN_R ; B = FM_GPU_PWR_EN
PR170  Q_RES  0 5% CHIP  pkg 0402LF  page 54 : A = SVID_PVDDCR_CPU0_P1_SVD_R ; B = SVID_PVDDCR_CPU0_P1_SVD

(kicad_pcb
	(version 20260206)
	(generator "pcbnew")
	(generator_version "10.0")
	(general
		(thickness 1.6)
		(legacy_teardrops no)
	)
	(paper "A4")
	(title_block
		(title "04192023_DAF0TMB3IC0_F0TG_MB_C_brd_V02_OCP.brd")
		(comment 1 "Grand Teton / footprints 2721-2722 of 8354")
	)
	(layers
		(0 "F.Cu" signal "TOP")
		(4 "In1.Cu" signal "GND")
		(6 "In2.Cu" signal "IN1")
		(8 "In3.Cu" signal "GND1")
		(10 "In4.Cu" signal "IN2")
		(12 "In5.Cu" signal "GND2")
		(14 "In6.Cu" signal "IN3")
		(16 "In7.Cu" signal "GND3")
		(18 "In8.Cu" signal "VCC")
		(20 "In9.Cu" signal "VCC1")
		(22 "In10.Cu" signal "GND4")
		(24 "In11.Cu" signal "IN4")
		(26 "In12.Cu" signal "GND5")
		(28 "In13.Cu" signal "IN5")
		(30 "In14.Cu" signal "GND6")
		(32 "In15.Cu" signal "IN6")
		(34 "In16.Cu" signal "GND7")
		(2 "B.Cu" signal "BOTTOM")
		(9 "F.Adhes" user "F.Adhesive")
		(11 "B.Adhes" user "B.Adhesive")
		(13 "F.Paste" user "Package Geometry/Pastemask Top")
		(15 "B.Paste" user "Package Geometry/Pastemask Bottom")
		(5 "F.SilkS" user "Ref Des/Silkscreen Top")
		(7 "B.SilkS" user "Ref Des/Silkscreen Bottom")
		(1 "F.Mask" user "Board Geometry/Soldermask Top")
		(3 "B.Mask" user "Board Geometry/Soldermask Bottom")
		(17 "Dwgs.User" user "User.Drawings")
		(19 "Cmts.User" user "User.Comments")
		(21 "Eco1.User" user "User.Eco1")
		(23 "Eco2.User" user "User.Eco2")
		(25 "Edge.Cuts" user "Board Geometry/Outline")
		(27 "Margin" user)
		(31 "F.CrtYd" user "Package Geometry/Place Bound Top")
		(29 "B.CrtYd" user "Package Geometry/Place Bound Bottom")
		(35 "F.Fab" user "Ref Des/Assembly Top")
		(33 "B.Fab" user "Ref Des/Assembly Bottom")
	)
	(footprint ""
		(layer "F.Cu")
		(at 208.926684 -111.576866 180)
		(property "Reference" "R2262"
			(at 0 0 180)
			(layer "F.SilkS")
			(hide yes)
			(effects
				(font
					(size 1.27 1.27)
				)
			)
		)
		(property "Value" ""
			(at 0 0 180)
			(layer "F.Fab")
			(effects
				(font
					(size 1.27 1.27)
				)
			)
		)
		(duplicate_pad_numbers_are_jumpers no)
		(fp_line
			(start 0.7874 0.4064)
			(end -0.7874 0.4064)
			(stroke
				(width 0.1524)
				(type default)
			)
			(layer "F.SilkS")
		)
		(fp_line
			(start 0.7874 -0.4064)
			(end 0.7874 0.4064)
			(stroke
				(width 0.1524)
				(type default)
			)
			(layer "F.SilkS")
		)
		(fp_line
			(start -0.7874 0.4064)
			(end -0.7874 -0.4064)
			(stroke
				(width 0.1524)
				(type default)
			)
			(layer "F.SilkS")
		)
		(fp_line
			(start -0.7874 -0.4064)
			(end 0.7874 -0.4064)
			(stroke
				(width 0.1524)
				(type default)
			)
			(layer "F.SilkS")
		)
		(fp_line
			(start 0.67945 0.3048)
			(end 0.120396 0.3048)
			(stroke
				(width 0.1)
				(type default)
			)
			(layer "F.Fab")
		)
		(fp_line
			(start 0.67945 -0.3048)
			(end 0.67945 0.3048)
			(stroke
				(width 0.1)
				(type default)
			)
			(layer "F.Fab")
		)
		(fp_line
			(start 0.12065 -0.2794)
			(end 0.12065 -0.3048)
			(stroke
				(width 0.1)
				(type default)
			)
			(layer "F.Fab")
		)
		(fp_line
			(start 0.12065 -0.3048)
			(end 0.67945 -0.3048)
			(stroke
				(width 0.1)
				(type default)
			)
			(layer "F.Fab")
		)
		(fp_line
			(start 0.120396 0.3048)
			(end 0.120396 0.2794)
			(stroke
				(width 0.1)
				(type default)
			)
			(layer "F.Fab")
		)
		(fp_line
			(start 0.120396 0.2794)
			(end -0.12065 0.2794)
			(stroke
				(width 0.1)
				(type default)
			)
			(layer "F.Fab")
		)
		(fp_line
			(start -0.12065 0.3048)
			(end -0.67945 0.3048)
			(stroke
				(width 0.1)
				(type default)
			)
			(layer "F.Fab")
		)
		(fp_line
			(start -0.12065 0.2794)
			(end -0.12065 0.3048)
			(stroke
				(width 0.1)
				(type default)
			)
			(layer "F.Fab")
		)
		(fp_line
			(start -0.12065 -0.2794)
			(end 0.12065 -0.2794)
			(stroke
				(width 0.1)
				(type default)
			)
			(layer "F.Fab")
		)
		(fp_line
			(start -0.12065 -0.305054)
			(end -0.12065 -0.2794)
			(stroke
				(width 0.1)
				(type default)
			)
			(layer "F.Fab")
		)
		(fp_line
			(start -0.67945 0.3048)
			(end -0.67945 -0.305054)
			(stroke
				(width 0.1)
				(type default)
			)
			(layer "F.Fab")
		)
		(fp_line
			(start -0.67945 -0.305054)
			(end -0.12065 -0.305054)
			(stroke
				(width 0.1)
				(type default)
			)
			(layer "F.Fab")
		)
		(pad "1" smd circle
			(at -0.40005 0 180)
			(size 0 0)
			(layers "F.Cu" "F.Mask" "F.Paste")
			(net "FM_GPU_PWR_EN_R")
		)
		(pad "2" smd circle
			(at 0.40005 0 180)
			(size 0 0)
			(layers "F.Cu" "F.Mask" "F.Paste")
			(net "FM_GPU_PWR_EN")
		)
	)
	(footprint ""
		(layer "F.Cu")
		(at 146.104864 -194.567048 90)
		(property "Reference" "PR170"
			(at 0 0 90)
			(layer "F.SilkS")
			(hide yes)
			(effects
				(font
					(size 1.27 1.27)
				)
			)
		)
		(property "Value" ""
			(at 0 0 90)
			(layer "F.Fab")
			(effects
				(font
					(size 1.27 1.27)
				)
			)
		)
		(duplicate_pad_numbers_are_jumpers no)
		(fp_line
			(start 0.7874 -0.4064)
			(end 0.7874 0.4064)
			(stroke
				(width 0.1524)
				(type default)
			)
			(layer "F.SilkS")
		)
		(fp_line
			(start -0.7874 -0.4064)
			(end 0.7874 -0.4064)
			(stroke
				(width 0.1524)
				(type default)
			)
			(layer "F.SilkS")
		)
		(fp_line
			(start 0.7874 0.4064)
			(end -0.7874 0.4064)
			(stroke
				(width 0.1524)
				(type default)
			)
			(layer "F.SilkS")
		)
		(fp_line
			(start -0.7874 0.4064)
			(end -0.7874 -0.4064)
			(stroke
				(width 0.1524)
				(type default)
			)
			(layer "F.SilkS")
		)
		(fp_line
			(start -0.12065 -0.305054)
			(end -0.12065 -0.2794)
			(stroke
				(width 0.1)
				(type default)
			)
			(layer "F.Fab")
		)
		(fp_line
			(start -0.67945 -0.305054)
			(end -0.12065 -0.305054)
			(stroke
				(width 0.1)
				(type default)
			)
			(layer "F.Fab")
		)
		(fp_line
			(start 0.67945 -0.3048)
			(end 0.67945 0.3048)
			(stroke
				(width 0.1)
				(type default)
			)
			(layer "F.Fab")
		)
		(fp_line
			(start 0.12065 -0.3048)
			(end 0.67945 -0.3048)
			(stroke
				(width 0.1)
				(type default)
			)
			(layer "F.Fab")
		)
		(fp_line
			(start 0.12065 -0.2794)
			(end 0.12065 -0.3048)
			(stroke
				(width 0.1)
				(type default)
			)
			(layer "F.Fab")
		)
		(fp_line
			(start -0.12065 -0.2794)
			(end 0.12065 -0.2794)
			(stroke
				(width 0.1)
				(type default)
			)
			(layer "F.Fab")
		)
		(fp_line
			(start 0.120396 0.2794)
			(end -0.12065 0.2794)
			(stroke
				(width 0.1)
				(type default)
			)
			(layer "F.Fab")
		)
		(fp_line
			(start -0.12065 0.2794)
			(end -0.12065 0.3048)
			(stroke
				(width 0.1)
				(type default)
			)
			(layer "F.Fab")
		)
		(fp_line
			(start 0.67945 0.3048)
			(end 0.120396 0.3048)
			(stroke
				(width 0.1)
				(type default)
			)
			(layer "F.Fab")
		)
		(fp_line
			(start 0.120396 0.3048)
			(end 0.120396 0.2794)
			(stroke
				(width 0.1)
				(type default)
			)
			(layer "F.Fab")
		)
		(fp_line
			(start -0.12065 0.3048)
			(end -0.67945 0.3048)
			(stroke
				(width 0.1)
				(type default)
			)
			(layer "F.Fab")
		)
		(fp_line
			(start -0.67945 0.3048)
			(end -0.67945 -0.305054)
			(stroke
				(width 0.1)
				(type default)
			)
			(layer "F.Fab")
		)
		(pad "1" smd circle
			(at -0.40005 0 90)
			(size 0 0)
			(layers "F.Cu" "F.Mask" "F.Paste")
			(net "SVID_PVDDCR_CPU0_P1_SVD_R")
		)
		(pad "2" smd circle
			(at 0.40005 0 90)
			(size 0 0)
			(layers "F.Cu" "F.Mask" "F.Paste")
			(net "SVID_PVDDCR_CPU0_P1_SVD")
		)
	)
)
